FILE_TYPE = CONNECTIVITY;
{Allegro Design Entry HDL 17.2-2016 S081 (4005846) 1/11/2022}
"PAGE_NUMBER" = 108;
0"NC";
1"M_L_CPU1_SA_DQ<31:0>";
2"M_L_CPU1_SB_DQS_DP<9:0>";
3"M_L_CPU1_SB_DQS_DN<9:0>";
4"M_L_CPU1_SA_DQS_DP<9:0>";
5"M_L_CPU1_SA_DQS_DN<9:0>";
6"M_L_CPU1_SB_DQ<31:0>";
7"M_L_CPU1_SB_CB<7:0>";
8"M_L_CPU1_SA_CB<7:0>";
9"M_L_CPU1_SB_CA<6:0>";
10"M_L_CPU1_SA_CA<6:0>";
11"GND\g";
12"GND\g";
13"P3V3_STBY\g";
14"GND\g";
15"GND\g";
16"GND\g";
17"P12V_MEM_1\g";
18"P3V3_STBY\g";
19"PD_CHL_CPU1_DIMM_SAA";
20"I3C_SPD_DDRGL_CPU1_SDA";
21"I3C_SPD_DDRL_CPU1_SCL";
22"I3C_SPD_DDRGL_CPU1_SCL";
23"M_L_CPU1_ALERT_N";
24"M_L_CPU1_RESET_N";
25"PWRGD_CHL_CPU1_DIMM";
26"M_L_CPU1_SB_CB<3>";
27"M_L_CPU1_SB_PAR";
28"M_L_CPU1_SA_CS_N<0>";
29"M_L_CPU1_SB_CS_N<1>";
30"PD_CHL_CPU1_DIMM_SAA";
31"PWRGD_CHGL_CPU1";
32"M_L_CPU1_SA_CB<7>";
33"M_L_CPU1_SA_CB<4>";
34"M_L_CPU1_SA_CB<1>";
35"M_L_CPU1_SB_CB<7>";
36"M_L_CPU1_SA_CA<0>";
37"M_L_CPU1_SB_CA<0>";
38"M_L_CPU1_SA_CA<1>";
39"M_L_CPU1_SB_CA<1>";
40"M_L_CPU1_SA_CA<2>";
41"M_L_CPU1_SB_CA<2>";
42"M_L_CPU1_SA_CA<3>";
43"M_L_CPU1_SB_CA<3>";
44"M_L_CPU1_SA_CA<4>";
45"M_L_CPU1_SB_CA<4>";
46"M_L_CPU1_SA_CA<5>";
47"M_L_CPU1_SB_CA<5>";
48"M_L_CPU1_SA_CA<6>";
49"M_L_CPU1_SB_CA<6>";
50"M_L_CPU1_SA_CB<6>";
51"M_L_CPU1_SA_CB<5>";
52"M_L_CPU1_SA_CB<3>";
53"M_L_CPU1_SA_CB<2>";
54"M_L_CPU1_SA_CB<0>";
55"M_L_CPU1_SB_CB<6>";
56"M_L_CPU1_SB_CB<5>";
57"M_L_CPU1_SB_CB<4>";
58"M_L_CPU1_SB_CB<2>";
59"M_L_CPU1_SB_CB<1>";
60"M_L_CPU1_SB_CB<0>";
61"M_L_CPU1_CLK_DN<0>";
62"M_L_CPU1_CLK_DP<0>";
63"M_L_CPU1_SB_CS_N<0>";
64"M_L_CPU1_SA_CS_N<1>";
65"M_L_CPU1_SA_DQ<20>";
66"M_L_CPU1_SA_DQ<19>";
67"M_L_CPU1_SA_DQ<18>";
68"M_L_CPU1_SA_DQ<17>";
69"M_L_CPU1_SA_DQ<16>";
70"M_L_CPU1_SA_DQ<13>";
71"M_L_CPU1_SA_DQ<12>";
72"M_L_CPU1_SA_DQ<11>";
73"M_L_CPU1_SA_DQ<10>";
74"M_L_CPU1_SA_DQ<9>";
75"M_L_CPU1_SA_DQ<8>";
76"M_L_CPU1_SA_DQ<7>";
77"M_L_CPU1_SA_DQ<6>";
78"M_L_CPU1_SA_DQ<5>";
79"M_L_CPU1_SA_DQ<4>";
80"M_L_CPU1_SA_DQ<3>";
81"M_L_CPU1_SA_DQ<2>";
82"M_L_CPU1_SA_DQ<1>";
83"M_L_CPU1_SA_DQ<0>";
84"M_L_CPU1_SB_DQ<31>";
85"M_L_CPU1_SB_DQ<30>";
86"M_L_CPU1_SB_DQ<29>";
87"M_L_CPU1_SB_DQ<28>";
88"M_L_CPU1_SB_DQ<27>";
89"M_L_CPU1_SB_DQ<26>";
90"M_L_CPU1_SB_DQ<25>";
91"M_L_CPU1_SB_DQ<24>";
92"M_L_CPU1_SB_DQ<23>";
93"M_L_CPU1_SB_DQ<22>";
94"M_L_CPU1_SB_DQ<21>";
95"M_L_CPU1_SB_DQ<20>";
96"M_L_CPU1_SB_DQ<19>";
97"M_L_CPU1_SB_DQ<18>";
98"M_L_CPU1_SB_DQ<17>";
99"M_L_CPU1_SB_DQ<16>";
100"M_L_CPU1_SB_DQ<15>";
101"M_L_CPU1_SB_DQ<14>";
102"M_L_CPU1_SB_DQ<13>";
103"M_L_CPU1_SB_DQ<12>";
104"M_L_CPU1_SB_DQ<11>";
105"M_L_CPU1_SB_DQ<10>";
106"M_L_CPU1_SB_DQ<9>";
107"M_L_CPU1_SB_DQ<8>";
108"M_L_CPU1_SB_DQ<7>";
109"M_L_CPU1_SB_DQ<6>";
110"M_L_CPU1_SB_DQ<5>";
111"M_L_CPU1_SB_DQ<4>";
112"M_L_CPU1_SB_DQ<3>";
113"M_L_CPU1_SB_DQ<2>";
114"M_L_CPU1_SB_DQ<1>";
115"M_L_CPU1_SB_DQ<0>";
116"M_L_CPU1_SA_RSP<0>";
117"M_L_CPU1_SB_RSP<0>";
118"M_L_CPU1_SA_PAR";
119"TP_CHL_CPU1_DIMM_RFU_6";
120"TP_CHL_CPU1_DIMM_RFU_5";
121"TP_CHL_CPU1_DIMM_RFU_4";
122"TP_CHL_CPU1_DIMM_RFU_3";
123"TP_CHL_CPU1_DIMM_RFU_2";
124"TP_CHL_CPU1_DIMM_RFU_1";
125"TP_CHL_CPU1_DIMM_RFU_0";
126"M_L_CPU1_SA_DQ<31>";
127"M_L_CPU1_SA_DQ<30>";
128"M_L_CPU1_SA_DQ<29>";
129"M_L_CPU1_SA_DQ<28>";
130"M_L_CPU1_SA_DQ<27>";
131"M_L_CPU1_SA_DQ<26>";
132"M_L_CPU1_SA_DQ<25>";
133"M_L_CPU1_SA_DQ<24>";
134"M_L_CPU1_SA_DQ<23>";
135"M_L_CPU1_SA_DQ<22>";
136"M_L_CPU1_SA_DQ<21>";
137"M_L_CPU1_SA_DQS_DN<7>";
138"M_L_CPU1_SA_DQS_DP<6>";
139"M_L_CPU1_SB_DQS_DP<8>";
140"M_L_CPU1_SB_DQS_DN<8>";
141"M_L_CPU1_SB_DQS_DP<7>";
142"M_L_CPU1_SA_DQS_DN<0>";
143"M_L_CPU1_SA_DQS_DP<0>";
144"M_L_CPU1_SB_DQS_DN<0>";
145"M_L_CPU1_SB_DQS_DP<0>";
146"M_L_CPU1_SA_DQS_DN<1>";
147"M_L_CPU1_SA_DQS_DP<1>";
148"M_L_CPU1_SB_DQS_DN<1>";
149"M_L_CPU1_SB_DQS_DP<1>";
150"M_L_CPU1_SA_DQS_DN<2>";
151"M_L_CPU1_SA_DQS_DP<2>";
152"M_L_CPU1_SB_DQS_DN<2>";
153"M_L_CPU1_SB_DQS_DP<2>";
154"M_L_CPU1_SA_DQS_DN<3>";
155"M_L_CPU1_SA_DQS_DP<3>";
156"M_L_CPU1_SB_DQS_DN<3>";
157"M_L_CPU1_SB_DQS_DP<3>";
158"M_L_CPU1_SA_DQS_DN<4>";
159"M_L_CPU1_SA_DQS_DP<4>";
160"M_L_CPU1_SB_DQS_DN<4>";
161"M_L_CPU1_SB_DQS_DP<4>";
162"M_L_CPU1_SA_DQS_DN<5>";
163"M_L_CPU1_SA_DQS_DP<5>";
164"M_L_CPU1_SB_DQS_DN<5>";
165"M_L_CPU1_SB_DQS_DP<5>";
166"M_L_CPU1_SA_DQS_DN<6>";
167"M_L_CPU1_SB_DQS_DN<6>";
168"M_L_CPU1_SB_DQS_DP<6>";
169"M_L_CPU1_SA_DQS_DP<7>";
170"M_L_CPU1_SB_DQS_DN<7>";
171"M_L_CPU1_SA_DQS_DN<8>";
172"M_L_CPU1_SA_DQS_DP<8>";
173"M_L_CPU1_SA_DQS_DN<9>";
174"M_L_CPU1_SA_DQS_DP<9>";
175"M_L_CPU1_SB_DQS_DN<9>";
176"M_L_CPU1_SB_DQS_DP<9>";
177"M_L_CPU1_SA_DQ<15>";
178"M_L_CPU1_SA_DQ<14>";
%"TAP"
"1","(-5950,4450)","0","mstr_standard","I100";
;
CDS_LIB"mstr_standard"
BODY_TYPE"PLUMBING"
HDL_TAP"TRUE";
"B \NAC \NWC"1;
"S \NAC"
BN"12"71;
%"TAP"
"1","(-5950,4400)","0","mstr_standard","I101";
;
CDS_LIB"mstr_standard"
BODY_TYPE"PLUMBING"
HDL_TAP"TRUE";
"B \NAC \NWC"1;
"S \NAC"
BN"11"72;
%"TAP"
"1","(-5950,4350)","0","mstr_standard","I102";
;
CDS_LIB"mstr_standard"
BODY_TYPE"PLUMBING"
HDL_TAP"TRUE";
"B \NAC \NWC"1;
"S \NAC"
BN"10"73;
%"TAP"
"1","(-5950,4300)","0","mstr_standard","I103";
;
CDS_LIB"mstr_standard"
BODY_TYPE"PLUMBING"
HDL_TAP"TRUE";
"B \NAC \NWC"1;
"S \NAC"
BN"9"74;
%"TAP"
"1","(-5950,4250)","0","mstr_standard","I104";
;
CDS_LIB"mstr_standard"
BODY_TYPE"PLUMBING"
HDL_TAP"TRUE";
"B \NAC \NWC"1;
"S \NAC"
BN"8"75;
%"TAP"
"1","(-5950,4600)","0","mstr_standard","I105";
;
CDS_LIB"mstr_standard"
BODY_TYPE"PLUMBING"
HDL_TAP"TRUE";
"B \NAC \NWC"1;
"S \NAC"
BN"15"177;
%"TAP"
"1","(-5950,4650)","0","mstr_standard","I106";
;
CDS_LIB"mstr_standard"
BODY_TYPE"PLUMBING"
HDL_TAP"TRUE";
"B \NAC \NWC"1;
"S \NAC"
BN"16"69;
%"TAP"
"1","(-5950,4700)","0","mstr_standard","I107";
;
CDS_LIB"mstr_standard"
BODY_TYPE"PLUMBING"
HDL_TAP"TRUE";
"B \NAC \NWC"1;
"S \NAC"
BN"17"68;
%"TAP"
"1","(-5950,4550)","0","mstr_standard","I108";
;
CDS_LIB"mstr_standard"
BODY_TYPE"PLUMBING"
HDL_TAP"TRUE";
"B \NAC \NWC"1;
"S \NAC"
BN"14"178;
%"TAP"
"1","(-5950,4500)","0","mstr_standard","I109";
;
CDS_LIB"mstr_standard"
BODY_TYPE"PLUMBING"
HDL_TAP"TRUE";
"B \NAC \NWC"1;
"S \NAC"
BN"13"70;
%"TAP"
"1","(-5950,4900)","0","mstr_standard","I110";
;
CDS_LIB"mstr_standard"
BODY_TYPE"PLUMBING"
HDL_TAP"TRUE";
"B \NAC \NWC"1;
"S \NAC"
BN"21"136;
%"TAP"
"1","(-5950,4950)","0","mstr_standard","I111";
;
CDS_LIB"mstr_standard"
BODY_TYPE"PLUMBING"
HDL_TAP"TRUE";
"B \NAC \NWC"1;
"S \NAC"
BN"22"135;
%"TAP"
"1","(-5950,4850)","0","mstr_standard","I112";
;
CDS_LIB"mstr_standard"
BODY_TYPE"PLUMBING"
HDL_TAP"TRUE";
"B \NAC \NWC"1;
"S \NAC"
BN"20"65;
%"TAP"
"1","(-5950,4800)","0","mstr_standard","I113";
;
CDS_LIB"mstr_standard"
BODY_TYPE"PLUMBING"
HDL_TAP"TRUE";
"B \NAC \NWC"1;
"S \NAC"
BN"19"66;
%"TAP"
"1","(-5950,4750)","0","mstr_standard","I114";
;
CDS_LIB"mstr_standard"
BODY_TYPE"PLUMBING"
HDL_TAP"TRUE";
"B \NAC \NWC"1;
"S \NAC"
BN"18"67;
%"TAP"
"1","(-5950,5150)","0","mstr_standard","I115";
;
CDS_LIB"mstr_standard"
BODY_TYPE"PLUMBING"
HDL_TAP"TRUE";
"B \NAC \NWC"1;
"S \NAC"
BN"26"131;
%"TAP"
"1","(-5950,5200)","0","mstr_standard","I116";
;
CDS_LIB"mstr_standard"
BODY_TYPE"PLUMBING"
HDL_TAP"TRUE";
"B \NAC \NWC"1;
"S \NAC"
BN"27"130;
%"TAP"
"1","(-5950,5100)","0","mstr_standard","I117";
;
CDS_LIB"mstr_standard"
BODY_TYPE"PLUMBING"
HDL_TAP"TRUE";
"B \NAC \NWC"1;
"S \NAC"
BN"25"132;
%"TAP"
"1","(-5950,5050)","0","mstr_standard","I118";
;
CDS_LIB"mstr_standard"
BODY_TYPE"PLUMBING"
HDL_TAP"TRUE";
"B \NAC \NWC"1;
"S \NAC"
BN"24"133;
%"TAP"
"1","(-5950,5000)","0","mstr_standard","I119";
;
CDS_LIB"mstr_standard"
BODY_TYPE"PLUMBING"
HDL_TAP"TRUE";
"B \NAC \NWC"1;
"S \NAC"
BN"23"134;
%"TAP"
"1","(-5950,5300)","0","mstr_standard","I120";
;
CDS_LIB"mstr_standard"
BODY_TYPE"PLUMBING"
HDL_TAP"TRUE";
"B \NAC \NWC"1;
"S \NAC"
BN"29"128;
%"TAP"
"1","(-5950,5400)","0","mstr_standard","I121";
;
CDS_LIB"mstr_standard"
BODY_TYPE"PLUMBING"
HDL_TAP"TRUE";
"B \NAC \NWC"1;
"S \NAC"
BN"31"126;
%"TAP"
"1","(-5950,5350)","0","mstr_standard","I122";
;
CDS_LIB"mstr_standard"
BODY_TYPE"PLUMBING"
HDL_TAP"TRUE";
"B \NAC \NWC"1;
"S \NAC"
BN"30"127;
%"TAP"
"1","(-5950,5250)","0","mstr_standard","I123";
;
CDS_LIB"mstr_standard"
BODY_TYPE"PLUMBING"
HDL_TAP"TRUE";
"B \NAC \NWC"1;
"S \NAC"
BN"28"129;
%"GND"
"1","(-6350,900)","0","mstr_symbols","I126";
;
BOM_COST"MEM"
SIZE"1B"
CDS_LIB"mstr_symbols"
BODY_TYPE"PLUMBING"
VOLTAGE"0.0"
HDL_POWER"GND";
"A\NAC"11;
%"Q_RES"
"2","(-6350,1125)","0","pure_quanta","I136";
;
LOCATION"R778"
$SEC"1"
CDS_SEC"1"
WATTAGE"1/16W"
MATERIAL"CHIP"
TOLERANCE"1%"
VALUE"84.5K"
PART_NUMBER"CS38452FB05"
PACK_TYPE"0402LF"
CDS_LIB"pure_quanta";
"A"
$PN"1"30;
"B"
$PN"2"11;
%"GND"
"1","(-2100,1900)","0","mstr_symbols","I137";
;
CDS_LIB"mstr_symbols"
SIZE"1B"
BODY_TYPE"PLUMBING"
VOLTAGE"0.0"
HDL_POWER"GND";
"A\NAC"14;
%"SCONN288_DDR506112002KQ"
"3","(-1200,3675)","0","pure_quanta","I138";
;
LOCATION"J37"
$SEC"3"
CDS_SEC"3"
VALUE"SCONN288_DDR506112002KQ"
PART_TYPE"SMLF"
MATERIAL"IO"
PART_NUMBER"DFHST8FS479"
CDS_LMAN_SYM_OUTLINE"-450,1800,450,-1750"
NEEDS_NO_SIZE"TRUE"
CDS_LIB"pure_quanta";
"G3"
$PN"G3"15;
"G2"
$PN"G2"15;
"G1"
$PN"G1"15;
"VSS62"
$PN"141"15;
"VSS61"
$PN"139"15;
"VSS60"
$PN"136"15;
"VSS58"
$PN"132"15;
"VSS104"
$PN"240"14;
"VSS102"
$PN"235"14;
"VSS100"
$PN"230"14;
"VIN_BULK2"
$PN"146"17;
"VIN_BULK1"
$PN"145"17;
"VIN_BULK0"
$PN"1"17;
"VSS126"
$PN"288"14;
"VSS125"
$PN"286"14;
"VSS124"
$PN"284"14;
"VSS123"
$PN"281"14;
"VSS122"
$PN"279"14;
"VSS121"
$PN"277"14;
"VSS120"
$PN"275"14;
"VSS119"
$PN"273"14;
"VSS118"
$PN"270"14;
"VSS117"
$PN"268"14;
"VSS116"
$PN"266"14;
"VSS115"
$PN"264"14;
"VSS114"
$PN"262"14;
"VSS113"
$PN"259"14;
"VSS112"
$PN"257"14;
"VSS111"
$PN"255"14;
"VSS110"
$PN"253"14;
"VSS109"
$PN"251"14;
"VSS108"
$PN"248"14;
"VSS107"
$PN"246"14;
"VSS106"
$PN"244"14;
"VSS105"
$PN"242"14;
"VSS103"
$PN"237"14;
"VSS101"
$PN"233"14;
"VSS99"
$PN"228"14;
"VSS98"
$PN"226"14;
"VSS97"
$PN"224"14;
"VSS96"
$PN"222"14;
"VSS95"
$PN"219"14;
"VSS94"
$PN"216"14;
"VSS93"
$PN"214"14;
"VSS92"
$PN"212"14;
"VSS91"
$PN"210"14;
"VSS90"
$PN"208"14;
"VSS89"
$PN"206"14;
"VSS88"
$PN"204"14;
"VSS87"
$PN"202"14;
"VSS86"
$PN"199"14;
"VSS85"
$PN"197"14;
"VSS84"
$PN"195"14;
"VSS83"
$PN"193"14;
"VSS82"
$PN"191"14;
"VSS81"
$PN"188"14;
"VSS80"
$PN"186"14;
"VSS79"
$PN"184"14;
"VSS78"
$PN"182"14;
"VSS77"
$PN"180"14;
"VSS76"
$PN"177"14;
"VSS75"
$PN"175"14;
"VSS74"
$PN"173"14;
"VSS73"
$PN"171"14;
"VSS72"
$PN"169"14;
"VSS71"
$PN"166"14;
"VSS70"
$PN"164"14;
"VSS69"
$PN"162"14;
"VSS68"
$PN"160"14;
"VSS67"
$PN"158"14;
"VSS66"
$PN"155"14;
"VSS65"
$PN"153"14;
"VSS64"
$PN"151"14;
"VSS63"
$PN"143"15;
"VSS59"
$PN"134"15;
"VSS57"
$PN"130"15;
"VSS56"
$PN"128"15;
"VSS55"
$PN"125"15;
"VSS54"
$PN"123"15;
"VSS53"
$PN"121"15;
"VSS52"
$PN"119"15;
"VSS51"
$PN"117"15;
"VSS50"
$PN"114"15;
"VSS49"
$PN"112"15;
"VSS48"
$PN"110"15;
"VSS47"
$PN"108"15;
"VSS46"
$PN"106"15;
"VSS45"
$PN"103"15;
"VSS44"
$PN"101"15;
"VSS43"
$PN"99"15;
"VSS42"
$PN"97"15;
"VSS41"
$PN"95"15;
"VSS40"
$PN"92"15;
"VSS39"
$PN"90"15;
"VSS38"
$PN"88"15;
"VSS37"
$PN"85"15;
"VSS36"
$PN"83"15;
"VSS35"
$PN"81"15;
"VSS34"
$PN"79"15;
"VSS33"
$PN"77"15;
"VSS32"
$PN"75"15;
"VSS31"
$PN"73"15;
"VSS30"
$PN"71"15;
"VSS29"
$PN"69"15;
"VSS28"
$PN"67"15;
"VSS27"
$PN"65"15;
"VSS26"
$PN"63"15;
"VSS25"
$PN"61"15;
"VSS24"
$PN"59"15;
"VSS23"
$PN"57"15;
"VSS22"
$PN"54"15;
"VSS21"
$PN"52"15;
"VSS20"
$PN"50"15;
"VSS19"
$PN"48"15;
"VSS18"
$PN"46"15;
"VSS17"
$PN"43"15;
"VSS16"
$PN"41"15;
"VSS15"
$PN"39"15;
"VSS14"
$PN"37"15;
"VSS13"
$PN"35"15;
"VSS12"
$PN"32"15;
"VSS11"
$PN"30"15;
"VSS10"
$PN"28"15;
"VSS9"
$PN"26"15;
"VSS8"
$PN"24"15;
"VSS7"
$PN"21"15;
"VSS6"
$PN"19"15;
"VSS5"
$PN"17"15;
"VSS4"
$PN"15"15;
"VSS3"
$PN"13"15;
"VSS2"
$PN"10"15;
"VSS1"
$PN"8"15;
"VSS0"
$PN"6"15;
%"GND"
"1","(-300,1675)","0","mstr_symbols","I139";
;
SIZE"1B"
CDS_LIB"mstr_symbols"
BODY_TYPE"PLUMBING"
VOLTAGE"0.0"
HDL_POWER"GND";
"A\NAC"15;
%"Q_CAP"
"1","(-8575,3225)","2","pure_quanta","I185";
;
LOCATION"C180"
$SEC"1"
CDS_SEC"1"
MATERIAL"X7R"
TOLERANCE"10%"
VALUE"0.1UF"
PART_NUMBER"CH4104K1B00"
VOLTAGE"25V"
PACK_TYPE"0402"
BOM_COST"MEM"
CDS_LIB"pure_quanta"
ROOM"MEM_CH_A_CPU0_DIMM1";
"B"
$PN"2"12;
"A"
$PN"1"18;
%"GND"
"1","(-8575,3000)","0","mstr_symbols","I186";
;
BOM_COST"MEM"
SIZE"1B"
CDS_LIB"mstr_symbols"
BODY_TYPE"PLUMBING"
VOLTAGE"0"
ROOM"MEM_EFGH_DECOUPLING_CAPS"
HDL_POWER"GND";
"A\NAC"12;
%"Q_RES"
"1","(-8450,2150)","2","pure_quanta","I188";
;
LOCATION"R314"
$SEC"1"
CDS_SEC"1"
VALUE"0"
BOM_COST"MEM"
CDS_LIB"pure_quanta"
WATTAGE"1/16W"
MATERIAL"CHIP"
TOLERANCE"5%"
PART_NUMBER"CS00002JB38"
PACK_TYPE"0402LF"
ROOM"RST_CPU0_PLD_TO_DIMM";
"B"
$PN"2"31;
"A"
$PN"1"25;
%"VCC_CORE"
"1","(-8325,2475)","0","mstr_symbols","I189";
;
HDL_POWER"P3V3_STBY"
CDS_LIB"mstr_symbols"
VOLTAGE"3.3"
ROOM"PVCCINFAON_CPU0_CTRL";
"A"13;
%"Q_RES"
"2","(-8325,2300)","0","pure_quanta","I190";
;
LOCATION"R115"
$SEC"1"
CDS_SEC"1"
TOLERANCE"5%"
WATTAGE"1/16W"
MATERIAL"EMPTY"
VALUE"1K"
PACK_TYPE"0402LF"
BOM_COST"MEM"
CDS_LIB"pure_quanta"
PART_NUMBER"TMP_QCS21002JB34"
ROOM"MEM_CH_A_CPU0_DIMM1";
"A"
$PN"1"13;
"B"
$PN"2"25;
%"TAP"
"1","(-3200,4275)","0","mstr_standard","I195";
;
CDS_LIB"mstr_standard"
BODY_TYPE"PLUMBING"
HDL_TAP"TRUE";
"B \NAC \NWC"5;
"S \NAC"
BN"9"173;
%"TAP"
"1","(-3200,4175)","0","mstr_standard","I196";
;
CDS_LIB"mstr_standard"
BODY_TYPE"PLUMBING"
HDL_TAP"TRUE";
"B \NAC \NWC"5;
"S \NAC"
BN"8"171;
%"TAP"
"1","(-3400,4225)","0","mstr_standard","I197";
;
CDS_LIB"mstr_standard"
BODY_TYPE"PLUMBING"
HDL_TAP"TRUE";
"B \NAC \NWC"4;
"S \NAC"
BN"8"172;
%"TAP"
"1","(-3400,4125)","0","mstr_standard","I198";
;
CDS_LIB"mstr_standard"
BODY_TYPE"PLUMBING"
HDL_TAP"TRUE";
"B \NAC \NWC"4;
"S \NAC"
BN"7"169;
%"TAP"
"1","(-3400,4325)","0","mstr_standard","I199";
;
CDS_LIB"mstr_standard"
BODY_TYPE"PLUMBING"
HDL_TAP"TRUE";
"B \NAC \NWC"4;
"S \NAC"
BN"9"174;
%"TAP"
"1","(-3200,4075)","0","mstr_standard","I200";
;
CDS_LIB"mstr_standard"
BODY_TYPE"PLUMBING"
HDL_TAP"TRUE";
"B \NAC \NWC"5;
"S \NAC"
BN"7"137;
%"TAP"
"1","(-3200,3975)","0","mstr_standard","I201";
;
CDS_LIB"mstr_standard"
BODY_TYPE"PLUMBING"
HDL_TAP"TRUE";
"B \NAC \NWC"5;
"S \NAC"
BN"6"166;
%"TAP"
"1","(-3200,3875)","0","mstr_standard","I202";
;
CDS_LIB"mstr_standard"
BODY_TYPE"PLUMBING"
HDL_TAP"TRUE";
"B \NAC \NWC"5;
"S \NAC"
BN"5"162;
%"TAP"
"1","(-3200,3775)","0","mstr_standard","I203";
;
CDS_LIB"mstr_standard"
BODY_TYPE"PLUMBING"
HDL_TAP"TRUE";
"B \NAC \NWC"5;
"S \NAC"
BN"4"158;
%"TAP"
"1","(-3200,3675)","0","mstr_standard","I204";
;
CDS_LIB"mstr_standard"
BODY_TYPE"PLUMBING"
HDL_TAP"TRUE";
"B \NAC \NWC"5;
"S \NAC"
BN"3"154;
%"TAP"
"1","(-3200,3575)","0","mstr_standard","I205";
;
CDS_LIB"mstr_standard"
BODY_TYPE"PLUMBING"
HDL_TAP"TRUE";
"B \NAC \NWC"5;
"S \NAC"
BN"2"150;
%"TAP"
"1","(-3200,3375)","0","mstr_standard","I206";
;
CDS_LIB"mstr_standard"
BODY_TYPE"PLUMBING"
HDL_TAP"TRUE";
"B \NAC \NWC"5;
"S \NAC"
BN"0"142;
%"TAP"
"1","(-3200,3475)","0","mstr_standard","I207";
;
CDS_LIB"mstr_standard"
BODY_TYPE"PLUMBING"
HDL_TAP"TRUE";
"B \NAC \NWC"5;
"S \NAC"
BN"1"146;
%"TAP"
"1","(-3200,3225)","0","mstr_standard","I208";
;
CDS_LIB"mstr_standard"
BODY_TYPE"PLUMBING"
HDL_TAP"TRUE";
"B \NAC \NWC"3;
"S \NAC"
BN"9"175;
%"TAP"
"1","(-3200,3125)","0","mstr_standard","I209";
;
CDS_LIB"mstr_standard"
BODY_TYPE"PLUMBING"
HDL_TAP"TRUE";
"B \NAC \NWC"3;
"S \NAC"
BN"8"140;
%"TAP"
"1","(-3400,3925)","0","mstr_standard","I210";
;
CDS_LIB"mstr_standard"
BODY_TYPE"PLUMBING"
HDL_TAP"TRUE";
"B \NAC \NWC"4;
"S \NAC"
BN"5"163;
%"TAP"
"1","(-3400,4025)","0","mstr_standard","I211";
;
CDS_LIB"mstr_standard"
BODY_TYPE"PLUMBING"
HDL_TAP"TRUE";
"B \NAC \NWC"4;
"S \NAC"
BN"6"138;
%"TAP"
"1","(-3400,3825)","0","mstr_standard","I212";
;
CDS_LIB"mstr_standard"
BODY_TYPE"PLUMBING"
HDL_TAP"TRUE";
"B \NAC \NWC"4;
"S \NAC"
BN"4"159;
%"TAP"
"1","(-3400,3725)","0","mstr_standard","I213";
;
CDS_LIB"mstr_standard"
BODY_TYPE"PLUMBING"
HDL_TAP"TRUE";
"B \NAC \NWC"4;
"S \NAC"
BN"3"155;
%"TAP"
"1","(-3400,3625)","0","mstr_standard","I214";
;
CDS_LIB"mstr_standard"
BODY_TYPE"PLUMBING"
HDL_TAP"TRUE";
"B \NAC \NWC"4;
"S \NAC"
BN"2"151;
%"TAP"
"1","(-3400,3425)","0","mstr_standard","I215";
;
CDS_LIB"mstr_standard"
BODY_TYPE"PLUMBING"
HDL_TAP"TRUE";
"B \NAC \NWC"4;
"S \NAC"
BN"0"143;
%"TAP"
"1","(-3400,3525)","0","mstr_standard","I216";
;
CDS_LIB"mstr_standard"
BODY_TYPE"PLUMBING"
HDL_TAP"TRUE";
"B \NAC \NWC"4;
"S \NAC"
BN"1"147;
%"TAP"
"1","(-3400,3275)","0","mstr_standard","I217";
;
CDS_LIB"mstr_standard"
BODY_TYPE"PLUMBING"
HDL_TAP"TRUE";
"B \NAC \NWC"2;
"S \NAC"
BN"9"176;
%"TAP"
"1","(-3400,3175)","0","mstr_standard","I218";
;
CDS_LIB"mstr_standard"
BODY_TYPE"PLUMBING"
HDL_TAP"TRUE";
"B \NAC \NWC"2;
"S \NAC"
BN"8"139;
%"TAP"
"1","(-3200,3025)","0","mstr_standard","I219";
;
CDS_LIB"mstr_standard"
BODY_TYPE"PLUMBING"
HDL_TAP"TRUE";
"B \NAC \NWC"3;
"S \NAC"
BN"7"170;
%"SCONN288_DDR506112002KQ"
"1","(-6800,3650)","0","pure_quanta","I22";
;
LOCATION"J37"
$SEC"1"
CDS_SEC"1"
PART_NUMBER"DFHST8FS479"
VALUE"SCONN288_DDR506112002KQ"
PART_TYPE"SMLF"
MATERIAL"IO"
CDS_LMAN_SYM_OUTLINE"-450,1900,450,-1850"
NEEDS_NO_SIZE"TRUE"
CDS_LIB"pure_quanta";
"PWR_GOOD||FAIL_N"
$PN"147"25;
"DQ31_A"
$PN"194"126;
"CB7_A"
$PN"205"32;
"CB4_A"
$PN"58"33;
"CB1_A"
$PN"53"34;
"CB7_B"
$PN"236"35;
"ALERT_N \B"
$PN"62"23;
"CA0_A"
$PN"66"36;
"CA0_B"
$PN"76"37;
"CA1_A"
$PN"211"38;
"CA1_B"
$PN"221"39;
"CA2_A"
$PN"68"40;
"CA2_B"
$PN"78"41;
"CA3_A"
$PN"213"42;
"CA3_B"
$PN"223"43;
"CA4_A"
$PN"70"44;
"CA4_B"
$PN"80"45;
"CA5_A"
$PN"215"46;
"CA5_B"
$PN"225"47;
"CA6_A"
$PN"72"48;
"CA6_B"
$PN"82"49;
"CB6_A"
$PN"203"50;
"CB5_A"
$PN"60"51;
"CB3_A"
$PN"198"52;
"CB2_A"
$PN"196"53;
"CB0_A"
$PN"51"54;
"CB6_B"
$PN"234"55;
"CB5_B"
$PN"91"56;
"CB4_B"
$PN"89"57;
"CB3_B"
$PN"243"26;
"CB2_B"
$PN"241"58;
"CB1_B"
$PN"98"59;
"CB0_B"
$PN"96"60;
"CK_C \B"
$PN"218"61;
"CK_T"
$PN"217"62;
"CS0_A_N"
$PN"64"28;
"CS0_B_N"
$PN"84"63;
"CS1_A_N"
$PN"209"64;
"CS1_B_N"
$PN"229"29;
"DQ30_A"
$PN"192"127;
"DQ29_A"
$PN"49"128;
"DQ28_A"
$PN"47"129;
"DQ27_A"
$PN"187"130;
"DQ26_A"
$PN"185"131;
"DQ25_A"
$PN"42"132;
"DQ24_A"
$PN"40"133;
"DQ23_A"
$PN"183"134;
"DQ22_A"
$PN"181"135;
"DQ21_A"
$PN"38"136;
"DQ20_A"
$PN"36"65;
"DQ19_A"
$PN"176"66;
"DQ18_A"
$PN"174"67;
"DQ17_A"
$PN"31"68;
"DQ16_A"
$PN"29"69;
"DQ15_A"
$PN"172"177;
"DQ14_A"
$PN"170"178;
"DQ13_A"
$PN"27"70;
"DQ12_A"
$PN"25"71;
"DQ11_A"
$PN"165"72;
"DQ10_A"
$PN"163"73;
"DQ9_A"
$PN"20"74;
"DQ8_A"
$PN"18"75;
"DQ7_A"
$PN"161"76;
"DQ6_A"
$PN"159"77;
"DQ5_A"
$PN"16"78;
"DQ4_A"
$PN"14"79;
"DQ3_A"
$PN"154"80;
"DQ2_A"
$PN"152"81;
"DQ1_A"
$PN"9"82;
"DQ0_A"
$PN"7"83;
"DQ31_B"
$PN"287"84;
"DQ30_B"
$PN"285"85;
"DQ29_B"
$PN"142"86;
"DQ28_B"
$PN"140"87;
"DQ27_B"
$PN"280"88;
"DQ26_B"
$PN"278"89;
"DQ25_B"
$PN"135"90;
"DQ24_B"
$PN"133"91;
"DQ23_B"
$PN"276"92;
"DQ22_B"
$PN"274"93;
"DQ21_B"
$PN"131"94;
"DQ20_B"
$PN"129"95;
"DQ19_B"
$PN"269"96;
"DQ18_B"
$PN"267"97;
"DQ17_B"
$PN"124"98;
"DQ16_B"
$PN"122"99;
"DQ15_B"
$PN"265"100;
"DQ14_B"
$PN"263"101;
"DQ13_B"
$PN"120"102;
"DQ12_B"
$PN"118"103;
"DQ11_B"
$PN"258"104;
"DQ10_B"
$PN"256"105;
"DQ9_B"
$PN"113"106;
"DQ8_B"
$PN"111"107;
"DQ7_B"
$PN"254"108;
"DQ6_B"
$PN"252"109;
"DQ5_B"
$PN"109"110;
"DQ4_B"
$PN"107"111;
"DQ3_B"
$PN"247"112;
"DQ2_B"
$PN"245"113;
"DQ1_B"
$PN"102"114;
"DQ0_B"
$PN"100"115;
"HAS"
$PN"148"19;
"HSCL"
$PN"4"21;
"HSDA"
$PN"5"20;
"LBD||RSP_A_N"
$PN"86"116;
"LBS||RSP_B_N"
$PN"87"117;
"PAR_A"
$PN"74"118;
"PAR_B"
$PN"227"27;
"RESET_N \B"
$PN"207"24;
"RFU6"
$PN"232"119;
"RFU5"
$PN"231"120;
"RFU4"
$PN"220"121;
"RFU3"
$PN"150"122;
"RFU2"
$PN"149"123;
"RFU1"
$PN"144"124;
"RFU0"
$PN"2"125;
"VIN_MGMT"
$PN"3"18;
%"TAP"
"1","(-3200,2925)","0","mstr_standard","I220";
;
CDS_LIB"mstr_standard"
BODY_TYPE"PLUMBING"
HDL_TAP"TRUE";
"B \NAC \NWC"3;
"S \NAC"
BN"6"167;
%"TAP"
"1","(-3200,2725)","0","mstr_standard","I221";
;
CDS_LIB"mstr_standard"
BODY_TYPE"PLUMBING"
HDL_TAP"TRUE";
"B \NAC \NWC"3;
"S \NAC"
BN"4"160;
%"TAP"
"1","(-3200,2825)","0","mstr_standard","I222";
;
CDS_LIB"mstr_standard"
BODY_TYPE"PLUMBING"
HDL_TAP"TRUE";
"B \NAC \NWC"3;
"S \NAC"
BN"5"164;
%"TAP"
"1","(-3200,2625)","0","mstr_standard","I223";
;
CDS_LIB"mstr_standard"
BODY_TYPE"PLUMBING"
HDL_TAP"TRUE";
"B \NAC \NWC"3;
"S \NAC"
BN"3"156;
%"TAP"
"1","(-3200,2525)","0","mstr_standard","I224";
;
CDS_LIB"mstr_standard"
BODY_TYPE"PLUMBING"
HDL_TAP"TRUE";
"B \NAC \NWC"3;
"S \NAC"
BN"2"152;
%"TAP"
"1","(-3200,2425)","0","mstr_standard","I225";
;
CDS_LIB"mstr_standard"
BODY_TYPE"PLUMBING"
HDL_TAP"TRUE";
"B \NAC \NWC"3;
"S \NAC"
BN"1"148;
%"TAP"
"1","(-3200,2325)","0","mstr_standard","I226";
;
CDS_LIB"mstr_standard"
BODY_TYPE"PLUMBING"
HDL_TAP"TRUE";
"B \NAC \NWC"3;
"S \NAC"
BN"0"144;
%"TAP"
"1","(-3400,2975)","0","mstr_standard","I227";
;
CDS_LIB"mstr_standard"
BODY_TYPE"PLUMBING"
HDL_TAP"TRUE";
"B \NAC \NWC"2;
"S \NAC"
BN"6"168;
%"TAP"
"1","(-3400,3075)","0","mstr_standard","I228";
;
CDS_LIB"mstr_standard"
BODY_TYPE"PLUMBING"
HDL_TAP"TRUE";
"B \NAC \NWC"2;
"S \NAC"
BN"7"141;
%"TAP"
"1","(-3400,2875)","0","mstr_standard","I229";
;
CDS_LIB"mstr_standard"
BODY_TYPE"PLUMBING"
HDL_TAP"TRUE";
"B \NAC \NWC"2;
"S \NAC"
BN"5"165;
%"TAP"
"1","(-7650,3200)","2","mstr_standard","I23";
;
CDS_LIB"mstr_standard"
BODY_TYPE"PLUMBING"
HDL_TAP"TRUE";
"B \NAC \NWC"7;
"S \NAC"
BN"0"60;
%"TAP"
"1","(-3400,2775)","0","mstr_standard","I230";
;
CDS_LIB"mstr_standard"
BODY_TYPE"PLUMBING"
HDL_TAP"TRUE";
"B \NAC \NWC"2;
"S \NAC"
BN"4"161;
%"TAP"
"1","(-3400,2675)","0","mstr_standard","I231";
;
CDS_LIB"mstr_standard"
BODY_TYPE"PLUMBING"
HDL_TAP"TRUE";
"B \NAC \NWC"2;
"S \NAC"
BN"3"157;
%"TAP"
"1","(-3400,2375)","0","mstr_standard","I232";
;
CDS_LIB"mstr_standard"
BODY_TYPE"PLUMBING"
HDL_TAP"TRUE";
"B \NAC \NWC"2;
"S \NAC"
BN"0"145;
%"TAP"
"1","(-3400,2575)","0","mstr_standard","I233";
;
CDS_LIB"mstr_standard"
BODY_TYPE"PLUMBING"
HDL_TAP"TRUE";
"B \NAC \NWC"2;
"S \NAC"
BN"2"153;
%"TAP"
"1","(-3400,2475)","0","mstr_standard","I234";
;
CDS_LIB"mstr_standard"
BODY_TYPE"PLUMBING"
HDL_TAP"TRUE";
"B \NAC \NWC"2;
"S \NAC"
BN"1"149;
%"SCONN288_DDR506112002KQ"
"2","(-4350,3325)","0","pure_quanta","I235";
;
LOCATION"J37"
$SEC"2"
CDS_SEC"2"
PART_TYPE"SMLF"
MATERIAL"IO"
PART_NUMBER"DFHST8FS479"
VALUE"SCONN288_DDR506112002KQ"
CDS_LMAN_SYM_OUTLINE"-600,1150,600,-1150"
NEEDS_NO_SIZE"TRUE"
CDS_LIB"pure_quanta";
"DQS7_A_C||TDQS7_A_C \B"
$PN"178"137;
"DQS6_A_T||TDQS6_A_T"
$PN"168"138;
"DQS8_B_T||TDQS8_B_T"
$PN"283"139;
"DQS8_B_C||TDQS8_B_C \B"
$PN"282"140;
"DQS7_B_T||TDQS7_B_T"
$PN"272"141;
"DQS0_A_C \B"
$PN"12"142;
"DQS0_A_T"
$PN"11"143;
"DQS0_B_C \B"
$PN"105"144;
"DQS0_B_T"
$PN"104"145;
"DQS1_A_C \B"
$PN"23"146;
"DQS1_A_T"
$PN"22"147;
"DQS1_B_C \B"
$PN"116"148;
"DQS1_B_T"
$PN"115"149;
"DQS2_A_C \B"
$PN"34"150;
"DQS2_A_T"
$PN"33"151;
"DQS2_B_C \B"
$PN"127"152;
"DQS2_B_T"
$PN"126"153;
"DQS3_A_C \B"
$PN"45"154;
"DQS3_A_T"
$PN"44"155;
"DQS3_B_C \B"
$PN"138"156;
"DQS3_B_T"
$PN"137"157;
"DQS4_A_C \B"
$PN"56"158;
"DQS4_A_T"
$PN"55"159;
"DQS4_B_C \B"
$PN"238"160;
"DQS4_B_T"
$PN"239"161;
"DQS5_A_C||TDQS5_A_C||DQS5_A_T||TDQS5_A_T \B"
$PN"156"162;
"DQS5_A_T||TDQS5_A_T"
$PN"157"163;
"DQS5_B_C||TDQS5_B_C \B"
$PN"249"164;
"DQS5_B_T||TDQS5_B_T"
$PN"250"165;
"DQS6_A_C||TDQS6_A_C||DQS6_A_T||TDQS6_A_T \B"
$PN"167"166;
"DQS6_B_C||TDQS6_B_C \B"
$PN"260"167;
"DQS6_B_T||TDQS6_B_T"
$PN"261"168;
"DQS7_A_T||TDQS7_A_T"
$PN"179"169;
"DQS7_B_C||TDQS7_B_C \B"
$PN"271"170;
"DQS8_A_C||TDQS8_A_C \B"
$PN"189"171;
"DQS8_A_T||TDQS8_A_T"
$PN"190"172;
"DQS9_A_C||TDQS9_A_C \B"
$PN"200"173;
"DQS9_A_T||TDQS9_A_T"
$PN"201"174;
"DQS9_B_C||TDQS9_B_C \B"
$PN"94"175;
"DQS9_B_T||TDQS9_B_T||DBI4_B_N"
$PN"93"176;
%"GND"
"1","(-2800,5500)","0","pure_quanta_power","I236";
;
SIZE"1B"
BOM_COST"MEM"
CDS_LIB"pure_quanta_power"
ROOM"MEM_EFGH_DECOUPLING_CAPS"
HDL_POWER"GND";
"A<SIZE-1..0>\NAC"16;
%"Q_CAP"
"1","(-2800,5850)","2","pure_quanta","I237";
;
LOCATION"C548"
$SEC"1"
CDS_SEC"1"
PART_NUMBER"CH6104KEA00"
VOLTAGE"25V"
PACK_TYPE"C0805"
MATERIAL"X6S"
TOLERANCE"10%"
VALUE"10UF"
CDS_LIB"pure_quanta"
BOM_COST"MEM"
ROOM"MEM_CH_A_CPU0_DIMM1";
"B"
$PN"2"16;
"A"
$PN"1"17;
%"Q_CAP"
"1","(-2225,5850)","2","pure_quanta","I238";
;
LOCATION"C549"
$SEC"1"
CDS_SEC"1"
MATERIAL"X6S"
TOLERANCE"10%"
VOLTAGE"25V"
PACK_TYPE"C0805"
VALUE"10UF"
PART_NUMBER"CH6104KEA00"
CDS_LIB"pure_quanta"
BOM_COST"MEM"
ROOM"MEM_CH_A_CPU0_DIMM1";
"B"
$PN"2"16;
"A"
$PN"1"17;
%"UNIVERSAL_POWER"
"1","(-2800,6175)","0","pure_quanta_power","I239";
;
HDL_POWER"P12V_MEM_1"
CDS_LIB"pure_quanta_power";
"A"17;
%"TAP"
"1","(-7650,3250)","2","mstr_standard","I24";
;
CDS_LIB"mstr_standard"
BODY_TYPE"PLUMBING"
HDL_TAP"TRUE";
"B \NAC \NWC"7;
"S \NAC"
BN"1"59;
%"Q_RES"
"1","(-7700,2700)","0","pure_quanta","I241";
;
$LOCATION"R1591"
CDS_LOCATION"R1591"
$SEC"1"
CDS_SEC"1"
VALUE"49.9"
CDS_LIB"pure_quanta"
MATERIAL"CHIP"
PACK_TYPE"0402LF"
WATTAGE"1/16W"
TOLERANCE"1%"
PART_NUMBER"CS04992FB07";
"B"
$PN"2"21;
"A"
$PN"1"22;
%"TAP"
"1","(-7650,3300)","2","mstr_standard","I25";
;
CDS_LIB"mstr_standard"
BODY_TYPE"PLUMBING"
HDL_TAP"TRUE";
"B \NAC \NWC"7;
"S \NAC"
BN"2"58;
%"TAP"
"1","(-7650,3400)","2","mstr_standard","I26";
;
CDS_LIB"mstr_standard"
BODY_TYPE"PLUMBING"
HDL_TAP"TRUE";
"B \NAC \NWC"7;
"S \NAC"
BN"4"57;
%"TAP"
"1","(-7650,3350)","2","mstr_standard","I27";
;
CDS_LIB"mstr_standard"
BODY_TYPE"PLUMBING"
HDL_TAP"TRUE";
"B \NAC \NWC"7;
"S \NAC"
BN"3"26;
%"TAP"
"1","(-7650,3450)","2","mstr_standard","I28";
;
CDS_LIB"mstr_standard"
BODY_TYPE"PLUMBING"
HDL_TAP"TRUE";
"B \NAC \NWC"7;
"S \NAC"
BN"5"56;
%"TAP"
"1","(-7650,3550)","2","mstr_standard","I29";
;
CDS_LIB"mstr_standard"
BODY_TYPE"PLUMBING"
HDL_TAP"TRUE";
"B \NAC \NWC"7;
"S \NAC"
BN"7"35;
%"TAP"
"1","(-7650,3650)","2","mstr_standard","I30";
;
CDS_LIB"mstr_standard"
BODY_TYPE"PLUMBING"
HDL_TAP"TRUE";
"B \NAC \NWC"8;
"S \NAC"
BN"0"54;
%"TAP"
"1","(-7650,3500)","2","mstr_standard","I31";
;
CDS_LIB"mstr_standard"
BODY_TYPE"PLUMBING"
HDL_TAP"TRUE";
"B \NAC \NWC"7;
"S \NAC"
BN"6"55;
%"TAP"
"1","(-5950,2300)","0","mstr_standard","I32";
;
CDS_LIB"mstr_standard"
BODY_TYPE"PLUMBING"
HDL_TAP"TRUE";
"B \NAC \NWC"6;
"S \NAC"
BN"2"113;
%"TAP"
"1","(-5950,2350)","0","mstr_standard","I33";
;
CDS_LIB"mstr_standard"
BODY_TYPE"PLUMBING"
HDL_TAP"TRUE";
"B \NAC \NWC"6;
"S \NAC"
BN"3"112;
%"TAP"
"1","(-5950,2400)","0","mstr_standard","I34";
;
CDS_LIB"mstr_standard"
BODY_TYPE"PLUMBING"
HDL_TAP"TRUE";
"B \NAC \NWC"6;
"S \NAC"
BN"4"111;
%"TAP"
"1","(-5950,2250)","0","mstr_standard","I35";
;
CDS_LIB"mstr_standard"
BODY_TYPE"PLUMBING"
HDL_TAP"TRUE";
"B \NAC \NWC"6;
"S \NAC"
BN"1"114;
%"TAP"
"1","(-5950,2200)","0","mstr_standard","I36";
;
CDS_LIB"mstr_standard"
BODY_TYPE"PLUMBING"
HDL_TAP"TRUE";
"B \NAC \NWC"6;
"S \NAC"
BN"0"115;
%"TAP"
"1","(-5950,2550)","0","mstr_standard","I37";
;
CDS_LIB"mstr_standard"
BODY_TYPE"PLUMBING"
HDL_TAP"TRUE";
"B \NAC \NWC"6;
"S \NAC"
BN"7"108;
%"TAP"
"1","(-5950,2650)","0","mstr_standard","I38";
;
CDS_LIB"mstr_standard"
BODY_TYPE"PLUMBING"
HDL_TAP"TRUE";
"B \NAC \NWC"6;
"S \NAC"
BN"9"106;
%"TAP"
"1","(-5950,2600)","0","mstr_standard","I39";
;
CDS_LIB"mstr_standard"
BODY_TYPE"PLUMBING"
HDL_TAP"TRUE";
"B \NAC \NWC"6;
"S \NAC"
BN"8"107;
%"TAP"
"1","(-5950,2500)","0","mstr_standard","I40";
;
CDS_LIB"mstr_standard"
BODY_TYPE"PLUMBING"
HDL_TAP"TRUE";
"B \NAC \NWC"6;
"S \NAC"
BN"6"109;
%"TAP"
"1","(-5950,2450)","0","mstr_standard","I41";
;
CDS_LIB"mstr_standard"
BODY_TYPE"PLUMBING"
HDL_TAP"TRUE";
"B \NAC \NWC"6;
"S \NAC"
BN"5"110;
%"TAP"
"1","(-5950,2850)","0","mstr_standard","I42";
;
CDS_LIB"mstr_standard"
BODY_TYPE"PLUMBING"
HDL_TAP"TRUE";
"B \NAC \NWC"6;
"S \NAC"
BN"13"102;
%"TAP"
"1","(-5950,2900)","0","mstr_standard","I43";
;
CDS_LIB"mstr_standard"
BODY_TYPE"PLUMBING"
HDL_TAP"TRUE";
"B \NAC \NWC"6;
"S \NAC"
BN"14"101;
%"TAP"
"1","(-5950,2800)","0","mstr_standard","I44";
;
CDS_LIB"mstr_standard"
BODY_TYPE"PLUMBING"
HDL_TAP"TRUE";
"B \NAC \NWC"6;
"S \NAC"
BN"12"103;
%"TAP"
"1","(-5950,2750)","0","mstr_standard","I45";
;
CDS_LIB"mstr_standard"
BODY_TYPE"PLUMBING"
HDL_TAP"TRUE";
"B \NAC \NWC"6;
"S \NAC"
BN"11"104;
%"TAP"
"1","(-5950,2700)","0","mstr_standard","I46";
;
CDS_LIB"mstr_standard"
BODY_TYPE"PLUMBING"
HDL_TAP"TRUE";
"B \NAC \NWC"6;
"S \NAC"
BN"10"105;
%"TAP"
"1","(-5950,3100)","0","mstr_standard","I47";
;
CDS_LIB"mstr_standard"
BODY_TYPE"PLUMBING"
HDL_TAP"TRUE";
"B \NAC \NWC"6;
"S \NAC"
BN"18"97;
%"TAP"
"1","(-5950,3150)","0","mstr_standard","I48";
;
CDS_LIB"mstr_standard"
BODY_TYPE"PLUMBING"
HDL_TAP"TRUE";
"B \NAC \NWC"6;
"S \NAC"
BN"19"96;
%"TAP"
"1","(-5950,3050)","0","mstr_standard","I49";
;
CDS_LIB"mstr_standard"
BODY_TYPE"PLUMBING"
HDL_TAP"TRUE";
"B \NAC \NWC"6;
"S \NAC"
BN"17"98;
%"VCC_CORE"
"1","(-8475,3425)","0","mstr_symbols","I5";
;
HDL_POWER"P3V3_STBY"
CDS_LIB"mstr_symbols"
VOLTAGE"3.3"
ROOM"PVCCINFAON_CPU1_CTRL";
"A"18;
%"TAP"
"1","(-5950,3000)","0","mstr_standard","I50";
;
CDS_LIB"mstr_standard"
BODY_TYPE"PLUMBING"
HDL_TAP"TRUE";
"B \NAC \NWC"6;
"S \NAC"
BN"16"99;
%"TAP"
"1","(-5950,2950)","0","mstr_standard","I51";
;
CDS_LIB"mstr_standard"
BODY_TYPE"PLUMBING"
HDL_TAP"TRUE";
"B \NAC \NWC"6;
"S \NAC"
BN"15"100;
%"TAP"
"1","(-5950,3350)","0","mstr_standard","I52";
;
CDS_LIB"mstr_standard"
BODY_TYPE"PLUMBING"
HDL_TAP"TRUE";
"B \NAC \NWC"6;
"S \NAC"
BN"23"92;
%"TAP"
"1","(-5950,3400)","0","mstr_standard","I53";
;
CDS_LIB"mstr_standard"
BODY_TYPE"PLUMBING"
HDL_TAP"TRUE";
"B \NAC \NWC"6;
"S \NAC"
BN"24"91;
%"TAP"
"1","(-5950,3300)","0","mstr_standard","I54";
;
CDS_LIB"mstr_standard"
BODY_TYPE"PLUMBING"
HDL_TAP"TRUE";
"B \NAC \NWC"6;
"S \NAC"
BN"22"93;
%"TAP"
"1","(-5950,3250)","0","mstr_standard","I55";
;
CDS_LIB"mstr_standard"
BODY_TYPE"PLUMBING"
HDL_TAP"TRUE";
"B \NAC \NWC"6;
"S \NAC"
BN"21"94;
%"TAP"
"1","(-5950,3200)","0","mstr_standard","I56";
;
CDS_LIB"mstr_standard"
BODY_TYPE"PLUMBING"
HDL_TAP"TRUE";
"B \NAC \NWC"6;
"S \NAC"
BN"20"95;
%"TAP"
"1","(-5950,3600)","0","mstr_standard","I57";
;
CDS_LIB"mstr_standard"
BODY_TYPE"PLUMBING"
HDL_TAP"TRUE";
"B \NAC \NWC"6;
"S \NAC"
BN"28"87;
%"TAP"
"1","(-5950,3650)","0","mstr_standard","I58";
;
CDS_LIB"mstr_standard"
BODY_TYPE"PLUMBING"
HDL_TAP"TRUE";
"B \NAC \NWC"6;
"S \NAC"
BN"29"86;
%"TAP"
"1","(-5950,3550)","0","mstr_standard","I59";
;
CDS_LIB"mstr_standard"
BODY_TYPE"PLUMBING"
HDL_TAP"TRUE";
"B \NAC \NWC"6;
"S \NAC"
BN"27"88;
%"TAP"
"1","(-5950,3500)","0","mstr_standard","I60";
;
CDS_LIB"mstr_standard"
BODY_TYPE"PLUMBING"
HDL_TAP"TRUE";
"B \NAC \NWC"6;
"S \NAC"
BN"26"89;
%"TAP"
"1","(-5950,3450)","0","mstr_standard","I61";
;
CDS_LIB"mstr_standard"
BODY_TYPE"PLUMBING"
HDL_TAP"TRUE";
"B \NAC \NWC"6;
"S \NAC"
BN"25"90;
%"TAP"
"1","(-7650,3700)","2","mstr_standard","I69";
;
CDS_LIB"mstr_standard"
BODY_TYPE"PLUMBING"
HDL_TAP"TRUE";
"B \NAC \NWC"8;
"S \NAC"
BN"1"34;
%"TAP"
"1","(-7650,3750)","2","mstr_standard","I70";
;
CDS_LIB"mstr_standard"
BODY_TYPE"PLUMBING"
HDL_TAP"TRUE";
"B \NAC \NWC"8;
"S \NAC"
BN"2"53;
%"TAP"
"1","(-7650,3800)","2","mstr_standard","I71";
;
CDS_LIB"mstr_standard"
BODY_TYPE"PLUMBING"
HDL_TAP"TRUE";
"B \NAC \NWC"8;
"S \NAC"
BN"3"52;
%"TAP"
"1","(-7650,3900)","2","mstr_standard","I72";
;
CDS_LIB"mstr_standard"
BODY_TYPE"PLUMBING"
HDL_TAP"TRUE";
"B \NAC \NWC"8;
"S \NAC"
BN"5"51;
%"TAP"
"1","(-7650,3850)","2","mstr_standard","I73";
;
CDS_LIB"mstr_standard"
BODY_TYPE"PLUMBING"
HDL_TAP"TRUE";
"B \NAC \NWC"8;
"S \NAC"
BN"4"33;
%"TAP"
"1","(-7650,3950)","2","mstr_standard","I74";
;
CDS_LIB"mstr_standard"
BODY_TYPE"PLUMBING"
HDL_TAP"TRUE";
"B \NAC \NWC"8;
"S \NAC"
BN"6"50;
%"TAP"
"1","(-7650,4000)","2","mstr_standard","I75";
;
CDS_LIB"mstr_standard"
BODY_TYPE"PLUMBING"
HDL_TAP"TRUE";
"B \NAC \NWC"8;
"S \NAC"
BN"7"32;
%"TAP"
"1","(-7650,4700)","2","mstr_standard","I76";
;
CDS_LIB"mstr_standard"
BODY_TYPE"PLUMBING"
HDL_TAP"TRUE";
"B \NAC \NWC"9;
"S \NAC"
BN"0"37;
%"TAP"
"1","(-7650,4800)","2","mstr_standard","I77";
;
CDS_LIB"mstr_standard"
BODY_TYPE"PLUMBING"
HDL_TAP"TRUE";
"B \NAC \NWC"9;
"S \NAC"
BN"2"41;
%"TAP"
"1","(-7650,4750)","2","mstr_standard","I78";
;
CDS_LIB"mstr_standard"
BODY_TYPE"PLUMBING"
HDL_TAP"TRUE";
"B \NAC \NWC"9;
"S \NAC"
BN"1"39;
%"TAP"
"1","(-7650,4850)","2","mstr_standard","I79";
;
CDS_LIB"mstr_standard"
BODY_TYPE"PLUMBING"
HDL_TAP"TRUE";
"B \NAC \NWC"9;
"S \NAC"
BN"3"43;
%"TAP"
"1","(-7650,4900)","2","mstr_standard","I80";
;
CDS_LIB"mstr_standard"
BODY_TYPE"PLUMBING"
HDL_TAP"TRUE";
"B \NAC \NWC"9;
"S \NAC"
BN"4"45;
%"TAP"
"1","(-7650,4950)","2","mstr_standard","I81";
;
CDS_LIB"mstr_standard"
BODY_TYPE"PLUMBING"
HDL_TAP"TRUE";
"B \NAC \NWC"9;
"S \NAC"
BN"5"47;
%"TAP"
"1","(-7650,5150)","2","mstr_standard","I82";
;
CDS_LIB"mstr_standard"
BODY_TYPE"PLUMBING"
HDL_TAP"TRUE";
"B \NAC \NWC"10;
"S \NAC"
BN"1"38;
%"TAP"
"1","(-7650,5200)","2","mstr_standard","I83";
;
CDS_LIB"mstr_standard"
BODY_TYPE"PLUMBING"
HDL_TAP"TRUE";
"B \NAC \NWC"10;
"S \NAC"
BN"2"40;
%"TAP"
"1","(-7650,5100)","2","mstr_standard","I84";
;
CDS_LIB"mstr_standard"
BODY_TYPE"PLUMBING"
HDL_TAP"TRUE";
"B \NAC \NWC"10;
"S \NAC"
BN"0"36;
%"TAP"
"1","(-7650,5000)","2","mstr_standard","I85";
;
CDS_LIB"mstr_standard"
BODY_TYPE"PLUMBING"
HDL_TAP"TRUE";
"B \NAC \NWC"9;
"S \NAC"
BN"6"49;
%"TAP"
"1","(-7650,5250)","2","mstr_standard","I86";
;
CDS_LIB"mstr_standard"
BODY_TYPE"PLUMBING"
HDL_TAP"TRUE";
"B \NAC \NWC"10;
"S \NAC"
BN"3"42;
%"TAP"
"1","(-7650,5300)","2","mstr_standard","I87";
;
CDS_LIB"mstr_standard"
BODY_TYPE"PLUMBING"
HDL_TAP"TRUE";
"B \NAC \NWC"10;
"S \NAC"
BN"4"44;
%"TAP"
"1","(-7650,5350)","2","mstr_standard","I88";
;
CDS_LIB"mstr_standard"
BODY_TYPE"PLUMBING"
HDL_TAP"TRUE";
"B \NAC \NWC"10;
"S \NAC"
BN"5"46;
%"TAP"
"1","(-7650,5400)","2","mstr_standard","I89";
;
CDS_LIB"mstr_standard"
BODY_TYPE"PLUMBING"
HDL_TAP"TRUE";
"B \NAC \NWC"10;
"S \NAC"
BN"6"48;
%"TAP"
"1","(-5950,3850)","0","mstr_standard","I90";
;
CDS_LIB"mstr_standard"
BODY_TYPE"PLUMBING"
HDL_TAP"TRUE";
"B \NAC \NWC"1;
"S \NAC"
BN"0"83;
%"TAP"
"1","(-5950,3900)","0","mstr_standard","I91";
;
CDS_LIB"mstr_standard"
BODY_TYPE"PLUMBING"
HDL_TAP"TRUE";
"B \NAC \NWC"1;
"S \NAC"
BN"1"82;
%"TAP"
"1","(-5950,3950)","0","mstr_standard","I92";
;
CDS_LIB"mstr_standard"
BODY_TYPE"PLUMBING"
HDL_TAP"TRUE";
"B \NAC \NWC"1;
"S \NAC"
BN"2"81;
%"TAP"
"1","(-5950,3750)","0","mstr_standard","I93";
;
CDS_LIB"mstr_standard"
BODY_TYPE"PLUMBING"
HDL_TAP"TRUE";
"B \NAC \NWC"6;
"S \NAC"
BN"31"84;
%"TAP"
"1","(-5950,3700)","0","mstr_standard","I94";
;
CDS_LIB"mstr_standard"
BODY_TYPE"PLUMBING"
HDL_TAP"TRUE";
"B \NAC \NWC"6;
"S \NAC"
BN"30"85;
%"TAP"
"1","(-5950,4100)","0","mstr_standard","I95";
;
CDS_LIB"mstr_standard"
BODY_TYPE"PLUMBING"
HDL_TAP"TRUE";
"B \NAC \NWC"1;
"S \NAC"
BN"5"78;
%"TAP"
"1","(-5950,4200)","0","mstr_standard","I96";
;
CDS_LIB"mstr_standard"
BODY_TYPE"PLUMBING"
HDL_TAP"TRUE";
"B \NAC \NWC"1;
"S \NAC"
BN"7"76;
%"TAP"
"1","(-5950,4150)","0","mstr_standard","I97";
;
CDS_LIB"mstr_standard"
BODY_TYPE"PLUMBING"
HDL_TAP"TRUE";
"B \NAC \NWC"1;
"S \NAC"
BN"6"77;
%"TAP"
"1","(-5950,4050)","0","mstr_standard","I98";
;
CDS_LIB"mstr_standard"
BODY_TYPE"PLUMBING"
HDL_TAP"TRUE";
"B \NAC \NWC"1;
"S \NAC"
BN"4"79;
%"TAP"
"1","(-5950,4000)","0","mstr_standard","I99";
;
CDS_LIB"mstr_standard"
BODY_TYPE"PLUMBING"
HDL_TAP"TRUE";
"B \NAC \NWC"1;
"S \NAC"
BN"3"80;
END.
